(kicad_pcb
	(version 20260206)
	(generator "pcbnew")
	(generator_version "10.0")
	(general
		(thickness 1.6)
		(legacy_teardrops no)
	)
	(paper "A4")
	(title_block
		(title "03242023_DA0F0TMBIJ0_F0T_Motherboard_J_brd_V01_OCP.brd")
		(comment 1 "Grand Teton / footprints 2752-2759 of 6105")
	)
	(layers
		(0 "F.Cu" signal "TOP")
		(4 "In1.Cu" signal "GND")
		(6 "In2.Cu" signal "IN1")
		(8 "In3.Cu" signal "GND1")
		(10 "In4.Cu" signal "IN2")
		(12 "In5.Cu" signal "GND2")
		(14 "In6.Cu" signal "IN3")
		(16 "In7.Cu" signal "GND3")
		(18 "In8.Cu" signal "VCC")
		(20 "In9.Cu" signal "VCC1")
		(22 "In10.Cu" signal "GND4")
		(24 "In11.Cu" signal "IN4")
		(26 "In12.Cu" signal "GND5")
		(28 "In13.Cu" signal "IN5")
		(30 "In14.Cu" signal "GND6")
		(32 "In15.Cu" signal "IN6")
		(34 "In16.Cu" signal "GND7")
		(2 "B.Cu" signal "BOTTOM")
		(9 "F.Adhes" user "F.Adhesive")
		(11 "B.Adhes" user "B.Adhesive")
		(13 "F.Paste" user "Package Geometry/Pastemask Top")
		(15 "B.Paste" user "Package Geometry/Pastemask Bottom")
		(5 "F.SilkS" user "Ref Des/Silkscreen Top")
		(7 "B.SilkS" user "Ref Des/Silkscreen Bottom")
		(1 "F.Mask" user "Board Geometry/Soldermask Top")
		(3 "B.Mask" user "Board Geometry/Soldermask Bottom")
		(17 "Dwgs.User" user "User.Drawings")
		(19 "Cmts.User" user "User.Comments")
		(21 "Eco1.User" user "User.Eco1")
		(23 "Eco2.User" user "User.Eco2")
		(25 "Edge.Cuts" user "Board Geometry/Outline")
		(27 "Margin" user)
		(31 "F.CrtYd" user "Package Geometry/Place Bound Top")
		(29 "B.CrtYd" user "Package Geometry/Place Bound Bottom")
		(35 "F.Fab" user "Ref Des/Assembly Top")
		(33 "B.Fab" user "Ref Des/Assembly Bottom")
	)
	(footprint ""
		(layer "F.Cu")
		(at 381.750824 -368.140742)
		(property "Reference" "PC1258"
			(at 0 0 0)
			(layer "F.SilkS")
			(hide yes)
			(effects
				(font
					(size 1.27 1.27)
				)
			)
		)
		(property "Value" ""
			(at 0 0 0)
			(layer "F.Fab")
			(effects
				(font
					(size 1.27 1.27)
				)
			)
		)
		(duplicate_pad_numbers_are_jumpers no)
		(fp_line
			(start -3.400044 1.249934)
			(end 3.400044 1.249934)
			(stroke
				(width 0.1524)
				(type default)
			)
			(layer "F.SilkS")
		)
		(fp_circle
			(center 0 1.249934)
			(end 3.400044 1.249934)
			(stroke
				(width 0.1524)
				(type default)
			)
			(fill no)
			(layer "F.SilkS")
		)
		(fp_poly
			(pts
				(arc
					(start 3.400044 1.249934)
					(mid 0 4.649978)
					(end -3.400044 1.249934)
				)
			)
			(stroke
				(width 0)
				(type default)
			)
			(fill yes)
			(layer "F.SilkS")
		)
		(fp_circle
			(center 0 1.249934)
			(end 3.400044 1.249934)
			(stroke
				(width 0.1)
				(type default)
			)
			(fill no)
			(layer "F.Fab")
		)
		(pad "1" thru_hole rect
			(at 0 0)
			(size 1.524 1.524)
			(drill 1.016)
			(layers "*.Cu" "*.Mask")
			(remove_unused_layers no)
			(net "PVPP_HBM_CPU0")
			(clearance 0)
			(padstack
				(mode front_inner_back)
				(layer "Inner"
					(shape circle)
					(size 1.524 1.524)
					(clearance 0)
				)
				(layer "B.Cu"
					(shape rect)
					(size 1.524 1.524)
					(clearance 0)
				)
			)
		)
		(pad "2" thru_hole circle
			(at 0 2.500122)
			(size 1.524 1.524)
			(drill 1.016)
			(layers "*.Cu" "*.Mask")
			(remove_unused_layers no)
			(net "GND")
			(clearance 0)
		)
	)
	(footprint ""
		(layer "F.Cu")
		(at 406.124664 -367.576862 180)
		(property "Reference" "R333"
			(at 0 0 180)
			(layer "F.SilkS")
			(hide yes)
			(effects
				(font
					(size 1.27 1.27)
				)
			)
		)
		(property "Value" ""
			(at 0 0 180)
			(layer "F.Fab")
			(effects
				(font
					(size 1.27 1.27)
				)
			)
		)
		(duplicate_pad_numbers_are_jumpers no)
		(fp_line
			(start 0.7874 0.4064)
			(end -0.7874 0.4064)
			(stroke
				(width 0.1524)
				(type default)
			)
			(layer "F.SilkS")
		)
		(fp_line
			(start 0.7874 -0.4064)
			(end 0.7874 0.4064)
			(stroke
				(width 0.1524)
				(type default)
			)
			(layer "F.SilkS")
		)
		(fp_line
			(start -0.7874 0.4064)
			(end -0.7874 -0.4064)
			(stroke
				(width 0.1524)
				(type default)
			)
			(layer "F.SilkS")
		)
		(fp_line
			(start -0.7874 -0.4064)
			(end 0.7874 -0.4064)
			(stroke
				(width 0.1524)
				(type default)
			)
			(layer "F.SilkS")
		)
		(fp_line
			(start 0.67945 0.3048)
			(end 0.120396 0.3048)
			(stroke
				(width 0.1)
				(type default)
			)
			(layer "F.Fab")
		)
		(fp_line
			(start 0.67945 -0.3048)
			(end 0.67945 0.3048)
			(stroke
				(width 0.1)
				(type default)
			)
			(layer "F.Fab")
		)
		(fp_line
			(start 0.12065 -0.2794)
			(end 0.12065 -0.3048)
			(stroke
				(width 0.1)
				(type default)
			)
			(layer "F.Fab")
		)
		(fp_line
			(start 0.12065 -0.3048)
			(end 0.67945 -0.3048)
			(stroke
				(width 0.1)
				(type default)
			)
			(layer "F.Fab")
		)
		(fp_line
			(start 0.120396 0.3048)
			(end 0.120396 0.2794)
			(stroke
				(width 0.1)
				(type default)
			)
			(layer "F.Fab")
		)
		(fp_line
			(start 0.120396 0.2794)
			(end -0.12065 0.2794)
			(stroke
				(width 0.1)
				(type default)
			)
			(layer "F.Fab")
		)
		(fp_line
			(start -0.12065 0.3048)
			(end -0.67945 0.3048)
			(stroke
				(width 0.1)
				(type default)
			)
			(layer "F.Fab")
		)
		(fp_line
			(start -0.12065 0.2794)
			(end -0.12065 0.3048)
			(stroke
				(width 0.1)
				(type default)
			)
			(layer "F.Fab")
		)
		(fp_line
			(start -0.12065 -0.2794)
			(end 0.12065 -0.2794)
			(stroke
				(width 0.1)
				(type default)
			)
			(layer "F.Fab")
		)
		(fp_line
			(start -0.12065 -0.305054)
			(end -0.12065 -0.2794)
			(stroke
				(width 0.1)
				(type default)
			)
			(layer "F.Fab")
		)
		(fp_line
			(start -0.67945 0.3048)
			(end -0.67945 -0.305054)
			(stroke
				(width 0.1)
				(type default)
			)
			(layer "F.Fab")
		)
		(fp_line
			(start -0.67945 -0.305054)
			(end -0.12065 -0.305054)
			(stroke
				(width 0.1)
				(type default)
			)
			(layer "F.Fab")
		)
		(pad "1" smd circle
			(at -0.40005 0 180)
			(size 0 0)
			(layers "F.Cu" "F.Mask" "F.Paste")
			(net "P3V3_AUX")
		)
		(pad "2" smd circle
			(at 0.40005 0 180)
			(size 0 0)
			(layers "F.Cu" "F.Mask" "F.Paste")
			(net "PD_PIROM_CPU0_ADDR1")
		)
	)
	(footprint ""
		(layer "F.Cu")
		(at 43.350942 -358.38003 -90)
		(property "Reference" "PC1198"
			(at 0 0 270)
			(layer "F.SilkS")
			(hide yes)
			(effects
				(font
					(size 1.27 1.27)
				)
			)
		)
		(property "Value" ""
			(at 0 0 270)
			(layer "F.Fab")
			(effects
				(font
					(size 1.27 1.27)
				)
			)
		)
		(duplicate_pad_numbers_are_jumpers no)
		(fp_line
			(start -0.7874 0.4064)
			(end -0.7874 -0.4064)
			(stroke
				(width 0.1524)
				(type default)
			)
			(layer "F.SilkS")
		)
		(fp_line
			(start 0.7874 0.4064)
			(end -0.7874 0.4064)
			(stroke
				(width 0.1524)
				(type default)
			)
			(layer "F.SilkS")
		)
		(fp_line
			(start -0.7874 -0.4064)
			(end 0.7874 -0.4064)
			(stroke
				(width 0.1524)
				(type default)
			)
			(layer "F.SilkS")
		)
		(fp_line
			(start 0.7874 -0.4064)
			(end 0.7874 0.4064)
			(stroke
				(width 0.1524)
				(type default)
			)
			(layer "F.SilkS")
		)
		(fp_line
			(start -0.67945 0.3048)
			(end -0.67945 -0.305054)
			(stroke
				(width 0.1)
				(type default)
			)
			(layer "F.Fab")
		)
		(fp_line
			(start -0.12065 0.3048)
			(end -0.67945 0.3048)
			(stroke
				(width 0.1)
				(type default)
			)
			(layer "F.Fab")
		)
		(fp_line
			(start 0.120396 0.3048)
			(end 0.120396 0.2794)
			(stroke
				(width 0.1)
				(type default)
			)
			(layer "F.Fab")
		)
		(fp_line
			(start 0.67945 0.3048)
			(end 0.120396 0.3048)
			(stroke
				(width 0.1)
				(type default)
			)
			(layer "F.Fab")
		)
		(fp_line
			(start -0.12065 0.2794)
			(end -0.12065 0.3048)
			(stroke
				(width 0.1)
				(type default)
			)
			(layer "F.Fab")
		)
		(fp_line
			(start 0.120396 0.2794)
			(end -0.12065 0.2794)
			(stroke
				(width 0.1)
				(type default)
			)
			(layer "F.Fab")
		)
		(fp_line
			(start -0.12065 -0.2794)
			(end 0.12065 -0.2794)
			(stroke
				(width 0.1)
				(type default)
			)
			(layer "F.Fab")
		)
		(fp_line
			(start 0.12065 -0.2794)
			(end 0.12065 -0.3048)
			(stroke
				(width 0.1)
				(type default)
			)
			(layer "F.Fab")
		)
		(fp_line
			(start 0.12065 -0.3048)
			(end 0.67945 -0.3048)
			(stroke
				(width 0.1)
				(type default)
			)
			(layer "F.Fab")
		)
		(fp_line
			(start 0.67945 -0.3048)
			(end 0.67945 0.3048)
			(stroke
				(width 0.1)
				(type default)
			)
			(layer "F.Fab")
		)
		(fp_line
			(start -0.67945 -0.305054)
			(end -0.12065 -0.305054)
			(stroke
				(width 0.1)
				(type default)
			)
			(layer "F.Fab")
		)
		(fp_line
			(start -0.12065 -0.305054)
			(end -0.12065 -0.2794)
			(stroke
				(width 0.1)
				(type default)
			)
			(layer "F.Fab")
		)
		(pad "1" smd circle
			(at -0.40005 0 270)
			(size 0 0)
			(layers "F.Cu" "F.Mask" "F.Paste")
			(net "SW_PVCCFA_EHV_FIVRA_CPU1_BOOT4_")
		)
		(pad "2" smd circle
			(at 0.40005 0 270)
			(size 0 0)
			(layers "F.Cu" "F.Mask" "F.Paste")
			(net "SW_PVCCFA_EHV_FIVRA_CPU1_BOOTR4")
		)
	)
	(footprint ""
		(layer "F.Cu")
		(at 424.204892 -392.648948)
		(property "Reference" "R2832"
			(at 0 0 0)
			(layer "F.SilkS")
			(hide yes)
			(effects
				(font
					(size 1.27 1.27)
				)
			)
		)
		(property "Value" ""
			(at 0 0 0)
			(layer "F.Fab")
			(effects
				(font
					(size 1.27 1.27)
				)
			)
		)
		(duplicate_pad_numbers_are_jumpers no)
		(fp_line
			(start -0.7874 -0.4064)
			(end 0.7874 -0.4064)
			(stroke
				(width 0.1524)
				(type default)
			)
			(layer "F.SilkS")
		)
		(fp_line
			(start -0.7874 0.4064)
			(end -0.7874 -0.4064)
			(stroke
				(width 0.1524)
				(type default)
			)
			(layer "F.SilkS")
		)
		(fp_line
			(start 0.7874 -0.4064)
			(end 0.7874 0.4064)
			(stroke
				(width 0.1524)
				(type default)
			)
			(layer "F.SilkS")
		)
		(fp_line
			(start 0.7874 0.4064)
			(end -0.7874 0.4064)
			(stroke
				(width 0.1524)
				(type default)
			)
			(layer "F.SilkS")
		)
		(fp_line
			(start -0.67945 -0.305054)
			(end -0.12065 -0.305054)
			(stroke
				(width 0.1)
				(type default)
			)
			(layer "F.Fab")
		)
		(fp_line
			(start -0.67945 0.3048)
			(end -0.67945 -0.305054)
			(stroke
				(width 0.1)
				(type default)
			)
			(layer "F.Fab")
		)
		(fp_line
			(start -0.12065 -0.305054)
			(end -0.12065 -0.2794)
			(stroke
				(width 0.1)
				(type default)
			)
			(layer "F.Fab")
		)
		(fp_line
			(start -0.12065 -0.2794)
			(end 0.12065 -0.2794)
			(stroke
				(width 0.1)
				(type default)
			)
			(layer "F.Fab")
		)
		(fp_line
			(start -0.12065 0.2794)
			(end -0.12065 0.3048)
			(stroke
				(width 0.1)
				(type default)
			)
			(layer "F.Fab")
		)
		(fp_line
			(start -0.12065 0.3048)
			(end -0.67945 0.3048)
			(stroke
				(width 0.1)
				(type default)
			)
			(layer "F.Fab")
		)
		(fp_line
			(start 0.120396 0.2794)
			(end -0.12065 0.2794)
			(stroke
				(width 0.1)
				(type default)
			)
			(layer "F.Fab")
		)
		(fp_line
			(start 0.120396 0.3048)
			(end 0.120396 0.2794)
			(stroke
				(width 0.1)
				(type default)
			)
			(layer "F.Fab")
		)
		(fp_line
			(start 0.12065 -0.3048)
			(end 0.67945 -0.3048)
			(stroke
				(width 0.1)
				(type default)
			)
			(layer "F.Fab")
		)
		(fp_line
			(start 0.12065 -0.2794)
			(end 0.12065 -0.3048)
			(stroke
				(width 0.1)
				(type default)
			)
			(layer "F.Fab")
		)
		(fp_line
			(start 0.67945 -0.3048)
			(end 0.67945 0.3048)
			(stroke
				(width 0.1)
				(type default)
			)
			(layer "F.Fab")
		)
		(fp_line
			(start 0.67945 0.3048)
			(end 0.120396 0.3048)
			(stroke
				(width 0.1)
				(type default)
			)
			(layer "F.Fab")
		)
		(pad "1" smd circle
			(at -0.40005 0)
			(size 0 0)
			(layers "F.Cu" "F.Mask" "F.Paste")
			(net "P3V3_AUX")
		)
		(pad "2" smd circle
			(at 0.40005 0)
			(size 0 0)
			(layers "F.Cu" "F.Mask" "F.Paste")
			(net "FM_SWB_BIC_READY_N")
		)
	)
	(footprint ""
		(layer "F.Cu")
		(at 116.21008 -106.238548 -90)
		(property "Reference" "R4045"
			(at 0 0 270)
			(layer "F.SilkS")
			(hide yes)
			(effects
				(font
					(size 1.27 1.27)
				)
			)
		)
		(property "Value" ""
			(at 0 0 270)
			(layer "F.Fab")
			(effects
				(font
					(size 1.27 1.27)
				)
			)
		)
		(duplicate_pad_numbers_are_jumpers no)
		(fp_line
			(start -0.7874 0.4064)
			(end -0.7874 -0.4064)
			(stroke
				(width 0.1524)
				(type default)
			)
			(layer "F.SilkS")
		)
		(fp_line
			(start 0.7874 0.4064)
			(end -0.7874 0.4064)
			(stroke
				(width 0.1524)
				(type default)
			)
			(layer "F.SilkS")
		)
		(fp_line
			(start -0.7874 -0.4064)
			(end 0.7874 -0.4064)
			(stroke
				(width 0.1524)
				(type default)
			)
			(layer "F.SilkS")
		)
		(fp_line
			(start 0.7874 -0.4064)
			(end 0.7874 0.4064)
			(stroke
				(width 0.1524)
				(type default)
			)
			(layer "F.SilkS")
		)
		(fp_line
			(start -0.67945 0.3048)
			(end -0.67945 -0.305054)
			(stroke
				(width 0.1)
				(type default)
			)
			(layer "F.Fab")
		)
		(fp_line
			(start -0.12065 0.3048)
			(end -0.67945 0.3048)
			(stroke
				(width 0.1)
				(type default)
			)
			(layer "F.Fab")
		)
		(fp_line
			(start 0.120396 0.3048)
			(end 0.120396 0.2794)
			(stroke
				(width 0.1)
				(type default)
			)
			(layer "F.Fab")
		)
		(fp_line
			(start 0.67945 0.3048)
			(end 0.120396 0.3048)
			(stroke
				(width 0.1)
				(type default)
			)
			(layer "F.Fab")
		)
		(fp_line
			(start -0.12065 0.2794)
			(end -0.12065 0.3048)
			(stroke
				(width 0.1)
				(type default)
			)
			(layer "F.Fab")
		)
		(fp_line
			(start 0.120396 0.2794)
			(end -0.12065 0.2794)
			(stroke
				(width 0.1)
				(type default)
			)
			(layer "F.Fab")
		)
		(fp_line
			(start -0.12065 -0.2794)
			(end 0.12065 -0.2794)
			(stroke
				(width 0.1)
				(type default)
			)
			(layer "F.Fab")
		)
		(fp_line
			(start 0.12065 -0.2794)
			(end 0.12065 -0.3048)
			(stroke
				(width 0.1)
				(type default)
			)
			(layer "F.Fab")
		)
		(fp_line
			(start 0.12065 -0.3048)
			(end 0.67945 -0.3048)
			(stroke
				(width 0.1)
				(type default)
			)
			(layer "F.Fab")
		)
		(fp_line
			(start 0.67945 -0.3048)
			(end 0.67945 0.3048)
			(stroke
				(width 0.1)
				(type default)
			)
			(layer "F.Fab")
		)
		(fp_line
			(start -0.67945 -0.305054)
			(end -0.12065 -0.305054)
			(stroke
				(width 0.1)
				(type default)
			)
			(layer "F.Fab")
		)
		(fp_line
			(start -0.12065 -0.305054)
			(end -0.12065 -0.2794)
			(stroke
				(width 0.1)
				(type default)
			)
			(layer "F.Fab")
		)
		(pad "1" smd circle
			(at -0.40005 0 270)
			(size 0 0)
			(layers "F.Cu" "F.Mask" "F.Paste")
			(net "RST_CPU0_DRAM_GH_PLD_LVT3_R_N")
		)
		(pad "2" smd circle
			(at 0.40005 0 270)
			(size 0 0)
			(layers "F.Cu" "F.Mask" "F.Paste")
			(net "RST_CPU0_DRAM_GH_PLD_LVT3_N")
		)
	)
	(footprint ""
		(layer "F.Cu")
		(at 279.0317 -424.69562)
		(property "Reference" "R4805"
			(at 0 0 0)
			(layer "F.SilkS")
			(hide yes)
			(effects
				(font
					(size 1.27 1.27)
				)
			)
		)
		(property "Value" ""
			(at 0 0 0)
			(layer "F.Fab")
			(effects
				(font
					(size 1.27 1.27)
				)
			)
		)
		(duplicate_pad_numbers_are_jumpers no)
		(fp_line
			(start -0.7874 -0.4064)
			(end 0.7874 -0.4064)
			(stroke
				(width 0.1524)
				(type default)
			)
			(layer "F.SilkS")
		)
		(fp_line
			(start -0.7874 0.4064)
			(end -0.7874 -0.4064)
			(stroke
				(width 0.1524)
				(type default)
			)
			(layer "F.SilkS")
		)
		(fp_line
			(start 0.7874 -0.4064)
			(end 0.7874 0.4064)
			(stroke
				(width 0.1524)
				(type default)
			)
			(layer "F.SilkS")
		)
		(fp_line
			(start 0.7874 0.4064)
			(end -0.7874 0.4064)
			(stroke
				(width 0.1524)
				(type default)
			)
			(layer "F.SilkS")
		)
		(fp_line
			(start -0.67945 -0.305054)
			(end -0.12065 -0.305054)
			(stroke
				(width 0.1)
				(type default)
			)
			(layer "F.Fab")
		)
		(fp_line
			(start -0.67945 0.3048)
			(end -0.67945 -0.305054)
			(stroke
				(width 0.1)
				(type default)
			)
			(layer "F.Fab")
		)
		(fp_line
			(start -0.12065 -0.305054)
			(end -0.12065 -0.2794)
			(stroke
				(width 0.1)
				(type default)
			)
			(layer "F.Fab")
		)
		(fp_line
			(start -0.12065 -0.2794)
			(end 0.12065 -0.2794)
			(stroke
				(width 0.1)
				(type default)
			)
			(layer "F.Fab")
		)
		(fp_line
			(start -0.12065 0.2794)
			(end -0.12065 0.3048)
			(stroke
				(width 0.1)
				(type default)
			)
			(layer "F.Fab")
		)
		(fp_line
			(start -0.12065 0.3048)
			(end -0.67945 0.3048)
			(stroke
				(width 0.1)
				(type default)
			)
			(layer "F.Fab")
		)
		(fp_line
			(start 0.120396 0.2794)
			(end -0.12065 0.2794)
			(stroke
				(width 0.1)
				(type default)
			)
			(layer "F.Fab")
		)
		(fp_line
			(start 0.120396 0.3048)
			(end 0.120396 0.2794)
			(stroke
				(width 0.1)
				(type default)
			)
			(layer "F.Fab")
		)
		(fp_line
			(start 0.12065 -0.3048)
			(end 0.67945 -0.3048)
			(stroke
				(width 0.1)
				(type default)
			)
			(layer "F.Fab")
		)
		(fp_line
			(start 0.12065 -0.2794)
			(end 0.12065 -0.3048)
			(stroke
				(width 0.1)
				(type default)
			)
			(layer "F.Fab")
		)
		(fp_line
			(start 0.67945 -0.3048)
			(end 0.67945 0.3048)
			(stroke
				(width 0.1)
				(type default)
			)
			(layer "F.Fab")
		)
		(fp_line
			(start 0.67945 0.3048)
			(end 0.120396 0.3048)
			(stroke
				(width 0.1)
				(type default)
			)
			(layer "F.Fab")
		)
		(pad "1" smd circle
			(at -0.40005 0)
			(size 0 0)
			(layers "F.Cu" "F.Mask" "F.Paste")
			(net "P3V3_AUX")
		)
		(pad "2" smd circle
			(at 0.40005 0)
			(size 0 0)
			(layers "F.Cu" "F.Mask" "F.Paste")
			(net "U369_VDD")
		)
	)
	(footprint ""
		(layer "F.Cu")
		(at 79.933038 -408.517344 -90)
		(property "Reference" "C688"
			(at 0 0 270)
			(layer "F.SilkS")
			(hide yes)
			(effects
				(font
					(size 1.27 1.27)
				)
			)
		)
		(property "Value" ""
			(at 0 0 270)
			(layer "F.Fab")
			(effects
				(font
					(size 1.27 1.27)
				)
			)
		)
		(duplicate_pad_numbers_are_jumpers no)
		(fp_line
			(start -0.299974 0.150114)
			(end -0.299974 -0.150114)
			(stroke
				(width 0.1)
				(type default)
			)
			(layer "F.Fab")
		)
		(fp_line
			(start 0.299974 0.150114)
			(end -0.299974 0.150114)
			(stroke
				(width 0.1)
				(type default)
			)
			(layer "F.Fab")
		)
		(fp_line
			(start -0.299974 -0.150114)
			(end 0.299974 -0.150114)
			(stroke
				(width 0.1)
				(type default)
			)
			(layer "F.Fab")
		)
		(fp_line
			(start 0.299974 -0.150114)
			(end 0.299974 0.150114)
			(stroke
				(width 0.1)
				(type default)
			)
			(layer "F.Fab")
		)
		(pad "1" smd rect
			(at -0.2667 0 270)
			(size 0.3048 0.381)
			(layers "F.Cu" "F.Mask" "F.Paste")
			(net "P5E_CPU1_PE4_TX_C_DN<10>")
		)
		(pad "2" smd rect
			(at 0.2667 0 270)
			(size 0.3048 0.381)
			(layers "F.Cu" "F.Mask" "F.Paste")
			(net "P5E_CPU1_PE4_TX_DN<10>")
		)
	)
	(footprint ""
		(layer "F.Cu")
		(at 82.996278 -408.517344 -90)
		(property "Reference" "C687"
			(at 0 0 270)
			(layer "F.SilkS")
			(hide yes)
			(effects
				(font
					(size 1.27 1.27)
				)
			)
		)
		(property "Value" ""
			(at 0 0 270)
			(layer "F.Fab")
			(effects
				(font
					(size 1.27 1.27)
				)
			)
		)
		(duplicate_pad_numbers_are_jumpers no)
		(fp_line
			(start -0.299974 0.150114)
			(end -0.299974 -0.150114)
			(stroke
				(width 0.1)
				(type default)
			)
			(layer "F.Fab")
		)
		(fp_line
			(start 0.299974 0.150114)
			(end -0.299974 0.150114)
			(stroke
				(width 0.1)
				(type default)
			)
			(layer "F.Fab")
		)
		(fp_line
			(start -0.299974 -0.150114)
			(end 0.299974 -0.150114)
			(stroke
				(width 0.1)
				(type default)
			)
			(layer "F.Fab")
		)
		(fp_line
			(start 0.299974 -0.150114)
			(end 0.299974 0.150114)
			(stroke
				(width 0.1)
				(type default)
			)
			(layer "F.Fab")
		)
		(pad "1" smd rect
			(at -0.2667 0 270)
			(size 0.3048 0.381)
			(layers "F.Cu" "F.Mask" "F.Paste")
			(net "P5E_CPU1_PE4_TX_C_DP<11>")
		)
		(pad "2" smd rect
			(at 0.2667 0 270)
			(size 0.3048 0.381)
			(layers "F.Cu" "F.Mask" "F.Paste")
			(net "P5E_CPU1_PE4_TX_DP<11>")
		)
	)
)
